(kicad_pcb
	(version 20241229)
	(generator "pcbnew")
	(generator_version "9.0")
	(general
		(thickness 1.599998)
		(legacy_teardrops no)
	)
	(paper "A4")
	(title_block
		(title "Artix - Datacenter Secure Control Module (DC-SCM)")
		(date "2024-11-06")
		(rev "1.1.3")
		(comment 9 "footprints 345-349 of 544")
	)
	(layers
		(0 "F.Cu" signal)
		(4 "In1.Cu" signal)
		(6 "In2.Cu" signal)
		(8 "In3.Cu" signal)
		(10 "In4.Cu" signal)
		(12 "In5.Cu" signal)
		(14 "In6.Cu" signal)
		(2 "B.Cu" signal)
		(9 "F.Adhes" user "F.Adhesive")
		(11 "B.Adhes" user "B.Adhesive")
		(13 "F.Paste" user)
		(15 "B.Paste" user)
		(5 "F.SilkS" user "F.Silkscreen")
		(7 "B.SilkS" user "B.Silkscreen")
		(1 "F.Mask" user)
		(3 "B.Mask" user)
		(17 "Dwgs.User" user "User.Drawings")
		(19 "Cmts.User" user "User.Comments")
		(21 "Eco1.User" user "User.Eco1")
		(23 "Eco2.User" user "User.Eco2")
		(25 "Edge.Cuts" user)
		(27 "Margin" user)
		(31 "F.CrtYd" user "F.Courtyard")
		(29 "B.CrtYd" user "B.Courtyard")
		(35 "F.Fab" user)
		(33 "B.Fab" user)
	)
	(footprint "antmicro-footprints:C_0603_1608Metric"
		(layer "B.Cu")
		(at 115.8 126.4 -90)
		(descr "Capacitor SMD 0603")
		(tags "capacitor 0603")
		(property "Reference" "C191"
			(at -1.4 0.6 90)
			(layer "B.SilkS")
			(effects
				(font
					(size 0.7 0.7)
					(thickness 0.15)
				)
				(justify left bottom mirror)
			)
		)
		(property "Value" "C_4u7_0603"
			(at 0 -1.6 90)
			(layer "B.Fab")
			(effects
				(font
					(size 0.7 0.7)
					(thickness 0.15)
				)
				(justify left bottom mirror)
			)
		)
		(property "Datasheet" "https://product.tdk.com/en/search/capacitor/ceramic/mlcc/info?part_no=C1608X5R1V475M080AC"
			(at 0 0 270)
			(layer "F.Fab")
			(hide yes)
			(effects
				(font
					(size 1.27 1.27)
					(thickness 0.15)
				)
			)
		)
		(property "Description" "SMD Multilayer Ceramic Capacitor, 4.7 µF, 35 V, 0603 [1608 Metric], ± 20%, X5R, C"
			(at 0 0 270)
			(layer "F.Fab")
			(hide yes)
			(effects
				(font
					(size 1.27 1.27)
					(thickness 0.15)
				)
			)
		)
		(property "Author" "Antmicro"
			(at -10.6 242.2 0)
			(layer "B.Fab")
			(hide yes)
			(effects
				(font
					(size 1 1)
					(thickness 0.15)
				)
				(justify mirror)
			)
		)
		(property "Dielectric" ""
			(at -10.6 242.2 0)
			(layer "B.Fab")
			(hide yes)
			(effects
				(font
					(size 1 1)
					(thickness 0.15)
				)
				(justify mirror)
			)
		)
		(property "License" "Apache-2.0"
			(at -10.6 242.2 0)
			(layer "B.Fab")
			(hide yes)
			(effects
				(font
					(size 1 1)
					(thickness 0.15)
				)
				(justify mirror)
			)
		)
		(property "MPN" "C1608X5R1V475M080AC"
			(at -10.6 242.2 0)
			(layer "B.Fab")
			(hide yes)
			(effects
				(font
					(size 1 1)
					(thickness 0.15)
				)
				(justify mirror)
			)
		)
		(property "Manufacturer" "TDK"
			(at -10.6 242.2 0)
			(layer "B.Fab")
			(hide yes)
			(effects
				(font
					(size 1 1)
					(thickness 0.15)
				)
				(justify mirror)
			)
		)
		(property "Val" "4u7"
			(at -10.6 242.2 0)
			(layer "B.Fab")
			(hide yes)
			(effects
				(font
					(size 1 1)
					(thickness 0.15)
				)
				(justify mirror)
			)
		)
		(property "Voltage" ""
			(at -10.6 242.2 0)
			(layer "B.Fab")
			(hide yes)
			(effects
				(font
					(size 1 1)
					(thickness 0.15)
				)
				(justify mirror)
			)
		)
		(sheetname "/Interfaces/")
		(sheetfile "interfaces.kicad_sch")
		(attr smd)
		(fp_line
			(start -0.15 0.4)
			(end 0.15 0.4)
			(stroke
				(width 0.15)
				(type solid)
			)
			(layer "B.SilkS")
		)
		(fp_line
			(start -0.15 -0.4)
			(end 0.15 -0.4)
			(stroke
				(width 0.15)
				(type solid)
			)
			(layer "B.SilkS")
		)
		(fp_rect
			(start -1.25 0.65)
			(end 1.25 -0.65)
			(stroke
				(width 0.05)
				(type solid)
			)
			(fill no)
			(layer "B.CrtYd")
		)
		(fp_rect
			(start -0.8 0.4)
			(end 0.8 -0.4)
			(stroke
				(width 0.15)
				(type solid)
			)
			(fill no)
			(layer "B.Fab")
		)
		(pad "1" smd roundrect
			(at -0.7 0 270)
			(size 0.8 1)
			(layers "B.Cu" "B.Mask" "B.Paste")
			(roundrect_rratio 0.2)
			(net 1 "GND")
			(pintype "passive")
		)
		(pad "2" smd roundrect
			(at 0.7 0 270)
			(size 0.8 1)
			(layers "B.Cu" "B.Mask" "B.Paste")
			(roundrect_rratio 0.2)
			(net 339 "VCC1V2")
			(pintype "passive")
		)
	)
	(footprint "antmicro-footprints:C_0402_1005Metric"
		(layer "B.Cu")
		(at 91.175 121.675)
		(descr "Capacitor SMD 0402")
		(tags "capacitor SMD 0402")
		(property "Reference" "C192"
			(at -3.675 0.325 0)
			(layer "B.SilkS")
			(effects
				(font
					(size 0.7 0.7)
					(thickness 0.15)
				)
				(justify right bottom mirror)
			)
		)
		(property "Value" "C_100n_6V3_0402"
			(at 0 -1.4 0)
			(layer "B.Fab")
			(effects
				(font
					(size 0.7 0.7)
					(thickness 0.15)
				)
				(justify right bottom mirror)
			)
		)
		(property "Datasheet" "https://www.passivecomponent.com/wp-content/uploads/datasheet/WTC_MLCC_General_Purpose.pdf"
			(at 0 0 0)
			(layer "F.Fab")
			(hide yes)
			(effects
				(font
					(size 1.27 1.27)
					(thickness 0.15)
				)
			)
		)
		(property "Description" "SMT Multilayer Ceramic Capacitor, 0.1 µF, 6.3 V, 0402 [1005 Metric], ± 10%, X5R, Walsin MLCC"
			(at 0 0 0)
			(layer "F.Fab")
			(hide yes)
			(effects
				(font
					(size 1.27 1.27)
					(thickness 0.15)
				)
			)
		)
		(property "Author" "Antmicro"
			(at 0 0 0)
			(layer "B.Fab")
			(hide yes)
			(effects
				(font
					(size 1 1)
					(thickness 0.15)
				)
				(justify mirror)
			)
		)
		(property "Dielectric" ""
			(at 0 0 0)
			(layer "B.Fab")
			(hide yes)
			(effects
				(font
					(size 1 1)
					(thickness 0.15)
				)
				(justify mirror)
			)
		)
		(property "License" "Apache-2.0"
			(at 0 0 0)
			(layer "B.Fab")
			(hide yes)
			(effects
				(font
					(size 1 1)
					(thickness 0.15)
				)
				(justify mirror)
			)
		)
		(property "MPN" "0402X104K6R3CT"
			(at 0 0 0)
			(layer "B.Fab")
			(hide yes)
			(effects
				(font
					(size 1 1)
					(thickness 0.15)
				)
				(justify mirror)
			)
		)
		(property "Manufacturer" "Walsin"
			(at 0 0 0)
			(layer "B.Fab")
			(hide yes)
			(effects
				(font
					(size 1 1)
					(thickness 0.15)
				)
				(justify mirror)
			)
		)
		(property "Public" "False"
			(at 0 0 0)
			(layer "B.Fab")
			(hide yes)
			(effects
				(font
					(size 1 1)
					(thickness 0.15)
				)
				(justify mirror)
			)
		)
		(property "Val" "100n"
			(at 0 0 0)
			(layer "B.Fab")
			(hide yes)
			(effects
				(font
					(size 1 1)
					(thickness 0.15)
				)
				(justify mirror)
			)
		)
		(property "Voltage" ""
			(at 0 0 0)
			(layer "B.Fab")
			(hide yes)
			(effects
				(font
					(size 1 1)
					(thickness 0.15)
				)
				(justify mirror)
			)
		)
		(sheetname "/Interfaces/")
		(sheetfile "interfaces.kicad_sch")
		(attr smd)
		(fp_rect
			(start -0.925 0.47)
			(end 0.925 -0.47)
			(stroke
				(width 0.05)
				(type default)
			)
			(fill no)
			(layer "B.CrtYd")
		)
		(fp_line
			(start -0.494 -0.248)
			(end -0.494 0.25)
			(stroke
				(width 0.15)
				(type solid)
			)
			(layer "B.Fab")
		)
		(fp_line
			(start -0.494 0.25)
			(end 0.504 0.25)
			(stroke
				(width 0.15)
				(type solid)
			)
			(layer "B.Fab")
		)
		(fp_line
			(start 0.504 -0.248)
			(end -0.494 -0.248)
			(stroke
				(width 0.15)
				(type solid)
			)
			(layer "B.Fab")
		)
		(fp_line
			(start 0.504 0.25)
			(end 0.504 -0.248)
			(stroke
				(width 0.15)
				(type solid)
			)
			(layer "B.Fab")
		)
		(pad "1" smd roundrect
			(at -0.48 0)
			(size 0.59 0.64)
			(layers "B.Cu" "B.Mask" "B.Paste")
			(roundrect_rratio 0.25)
			(net 1 "GND")
			(pintype "passive")
		)
		(pad "2" smd roundrect
			(at 0.48 0)
			(size 0.59 0.64)
			(layers "B.Cu" "B.Mask" "B.Paste")
			(roundrect_rratio 0.25)
			(net 339 "VCC1V2")
			(pintype "passive")
		)
	)
	(footprint "antmicro-footprints:C_0402_1005Metric"
		(layer "B.Cu")
		(at 95.925 162.485 90)
		(descr "Capacitor SMD 0402")
		(tags "capacitor SMD 0402")
		(property "Reference" "C194"
			(at -3.715 0.375 90)
			(layer "B.SilkS")
			(effects
				(font
					(size 0.7 0.7)
					(thickness 0.15)
				)
				(justify right bottom mirror)
			)
		)
		(property "Value" "C_100n_6V3_0402"
			(at 0 -1.4 90)
			(layer "B.Fab")
			(effects
				(font
					(size 0.7 0.7)
					(thickness 0.15)
				)
				(justify right bottom mirror)
			)
		)
		(property "Datasheet" "https://www.passivecomponent.com/wp-content/uploads/datasheet/WTC_MLCC_General_Purpose.pdf"
			(at 0 0 90)
			(layer "F.Fab")
			(hide yes)
			(effects
				(font
					(size 1.27 1.27)
					(thickness 0.15)
				)
			)
		)
		(property "Description" "SMT Multilayer Ceramic Capacitor, 0.1 µF, 6.3 V, 0402 [1005 Metric], ± 10%, X5R, Walsin MLCC"
			(at 0 0 90)
			(layer "F.Fab")
			(hide yes)
			(effects
				(font
					(size 1.27 1.27)
					(thickness 0.15)
				)
			)
		)
		(property "Author" "Antmicro"
			(at 258.41 66.56 0)
			(layer "B.Fab")
			(hide yes)
			(effects
				(font
					(size 1 1)
					(thickness 0.15)
				)
				(justify mirror)
			)
		)
		(property "Dielectric" ""
			(at 258.41 66.56 0)
			(layer "B.Fab")
			(hide yes)
			(effects
				(font
					(size 1 1)
					(thickness 0.15)
				)
				(justify mirror)
			)
		)
		(property "License" "Apache-2.0"
			(at 258.41 66.56 0)
			(layer "B.Fab")
			(hide yes)
			(effects
				(font
					(size 1 1)
					(thickness 0.15)
				)
				(justify mirror)
			)
		)
		(property "MPN" "0402X104K6R3CT"
			(at 258.41 66.56 0)
			(layer "B.Fab")
			(hide yes)
			(effects
				(font
					(size 1 1)
					(thickness 0.15)
				)
				(justify mirror)
			)
		)
		(property "Manufacturer" "Walsin"
			(at 258.41 66.56 0)
			(layer "B.Fab")
			(hide yes)
			(effects
				(font
					(size 1 1)
					(thickness 0.15)
				)
				(justify mirror)
			)
		)
		(property "Public" "False"
			(at 258.41 66.56 0)
			(layer "B.Fab")
			(hide yes)
			(effects
				(font
					(size 1 1)
					(thickness 0.15)
				)
				(justify mirror)
			)
		)
		(property "Val" "100n"
			(at 258.41 66.56 0)
			(layer "B.Fab")
			(hide yes)
			(effects
				(font
					(size 1 1)
					(thickness 0.15)
				)
				(justify mirror)
			)
		)
		(property "Voltage" ""
			(at 258.41 66.56 0)
			(layer "B.Fab")
			(hide yes)
			(effects
				(font
					(size 1 1)
					(thickness 0.15)
				)
				(justify mirror)
			)
		)
		(sheetname "/Interfaces/")
		(sheetfile "interfaces.kicad_sch")
		(attr smd)
		(fp_rect
			(start -0.925 0.47)
			(end 0.925 -0.47)
			(stroke
				(width 0.05)
				(type default)
			)
			(fill no)
			(layer "B.CrtYd")
		)
		(fp_line
			(start 0.504 -0.248)
			(end -0.494 -0.248)
			(stroke
				(width 0.15)
				(type solid)
			)
			(layer "B.Fab")
		)
		(fp_line
			(start -0.494 -0.248)
			(end -0.494 0.25)
			(stroke
				(width 0.15)
				(type solid)
			)
			(layer "B.Fab")
		)
		(fp_line
			(start 0.504 0.25)
			(end 0.504 -0.248)
			(stroke
				(width 0.15)
				(type solid)
			)
			(layer "B.Fab")
		)
		(fp_line
			(start -0.494 0.25)
			(end 0.504 0.25)
			(stroke
				(width 0.15)
				(type solid)
			)
			(layer "B.Fab")
		)
		(pad "1" smd roundrect
			(at -0.48 0 90)
			(size 0.59 0.64)
			(layers "B.Cu" "B.Mask" "B.Paste")
			(roundrect_rratio 0.25)
			(net 377 "PCIE_BMC_TX_N")
			(pintype "passive")
		)
		(pad "2" smd roundrect
			(at 0.48 0 90)
			(size 0.59 0.64)
			(layers "B.Cu" "B.Mask" "B.Paste")
			(roundrect_rratio 0.25)
			(net 489 "/Interfaces/PCIE_BMC_TX_C_N")
			(pintype "passive")
		)
	)
	(footprint "antmicro-footprints:C_0402_1005Metric"
		(layer "B.Cu")
		(at 105.76 98.12 -90)
		(descr "Capacitor SMD 0402")
		(tags "capacitor SMD 0402")
		(property "Reference" "C198"
			(at -3.62 -0.36 90)
			(layer "B.SilkS")
			(effects
				(font
					(size 0.7 0.7)
					(thickness 0.15)
				)
				(justify left bottom mirror)
			)
		)
		(property "Value" "C_4u7_0402"
			(at 0 -1.4 90)
			(layer "B.Fab")
			(effects
				(font
					(size 0.7 0.7)
					(thickness 0.15)
				)
				(justify left bottom mirror)
			)
		)
		(property "Datasheet" "https://www.murata.com/products/productdetail?partno=GRM155R61A475MEAA%23"
			(at 0 0 270)
			(layer "F.Fab")
			(hide yes)
			(effects
				(font
					(size 1.27 1.27)
					(thickness 0.15)
				)
			)
		)
		(property "Description" "SMD Multilayer Ceramic Capacitor, 4.7 µF, 10 V, 0402 [1005 Metric], ± 20%, X5R, GRM Series"
			(at 0 0 270)
			(layer "F.Fab")
			(hide yes)
			(effects
				(font
					(size 1.27 1.27)
					(thickness 0.15)
				)
			)
		)
		(property "Author" "Antmicro"
			(at 7.64 203.88 0)
			(layer "B.Fab")
			(hide yes)
			(effects
				(font
					(size 1 1)
					(thickness 0.15)
				)
				(justify mirror)
			)
		)
		(property "Dielectric" ""
			(at 7.64 203.88 0)
			(layer "B.Fab")
			(hide yes)
			(effects
				(font
					(size 1 1)
					(thickness 0.15)
				)
				(justify mirror)
			)
		)
		(property "License" "Apache-2.0"
			(at 7.64 203.88 0)
			(layer "B.Fab")
			(hide yes)
			(effects
				(font
					(size 1 1)
					(thickness 0.15)
				)
				(justify mirror)
			)
		)
		(property "MPN" "GRM155R61A475MEAAD"
			(at 7.64 203.88 0)
			(layer "B.Fab")
			(hide yes)
			(effects
				(font
					(size 1 1)
					(thickness 0.15)
				)
				(justify mirror)
			)
		)
		(property "Manufacturer" "Murata"
			(at 7.64 203.88 0)
			(layer "B.Fab")
			(hide yes)
			(effects
				(font
					(size 1 1)
					(thickness 0.15)
				)
				(justify mirror)
			)
		)
		(property "Val" "4u7"
			(at 7.64 203.88 0)
			(layer "B.Fab")
			(hide yes)
			(effects
				(font
					(size 1 1)
					(thickness 0.15)
				)
				(justify mirror)
			)
		)
		(property "Voltage" ""
			(at 7.64 203.88 0)
			(layer "B.Fab")
			(hide yes)
			(effects
				(font
					(size 1 1)
					(thickness 0.15)
				)
				(justify mirror)
			)
		)
		(sheetname "/Ethernet/")
		(sheetfile "ethernet.kicad_sch")
		(attr smd)
		(fp_rect
			(start -0.925 0.47)
			(end 0.925 -0.47)
			(stroke
				(width 0.05)
				(type default)
			)
			(fill no)
			(layer "B.CrtYd")
		)
		(fp_line
			(start -0.494 0.25)
			(end 0.504 0.25)
			(stroke
				(width 0.15)
				(type solid)
			)
			(layer "B.Fab")
		)
		(fp_line
			(start 0.504 0.25)
			(end 0.504 -0.248)
			(stroke
				(width 0.15)
				(type solid)
			)
			(layer "B.Fab")
		)
		(fp_line
			(start -0.494 -0.248)
			(end -0.494 0.25)
			(stroke
				(width 0.15)
				(type solid)
			)
			(layer "B.Fab")
		)
		(fp_line
			(start 0.504 -0.248)
			(end -0.494 -0.248)
			(stroke
				(width 0.15)
				(type solid)
			)
			(layer "B.Fab")
		)
		(pad "1" smd roundrect
			(at -0.48 0 270)
			(size 0.59 0.64)
			(layers "B.Cu" "B.Mask" "B.Paste")
			(roundrect_rratio 0.25)
			(net 1 "GND")
			(pintype "passive")
		)
		(pad "2" smd roundrect
			(at 0.48 0 270)
			(size 0.59 0.64)
			(layers "B.Cu" "B.Mask" "B.Paste")
			(roundrect_rratio 0.25)
			(net 2 "VCC3V3")
			(pintype "passive")
		)
	)
	(footprint "antmicro-footprints:C_0402_1005Metric"
		(layer "B.Cu")
		(at 102.75 90.765 -90)
		(descr "Capacitor SMD 0402")
		(tags "capacitor SMD 0402")
		(property "Reference" "C200"
			(at -3.649 -0.4 90)
			(layer "B.SilkS")
			(effects
				(font
					(size 0.7 0.7)
					(thickness 0.15)
				)
				(justify left bottom mirror)
			)
		)
		(property "Value" "C_4u7_0402"
			(at 0 -1.4 90)
			(layer "B.Fab")
			(effects
				(font
					(size 0.7 0.7)
					(thickness 0.15)
				)
				(justify left bottom mirror)
			)
		)
		(property "Datasheet" "https://www.murata.com/products/productdetail?partno=GRM155R61A475MEAA%23"
			(at 0 0 270)
			(layer "F.Fab")
			(hide yes)
			(effects
				(font
					(size 1.27 1.27)
					(thickness 0.15)
				)
			)
		)
		(property "Description" "SMD Multilayer Ceramic Capacitor, 4.7 µF, 10 V, 0402 [1005 Metric], ± 20%, X5R, GRM Series"
			(at 0 0 270)
			(layer "F.Fab")
			(hide yes)
			(effects
				(font
					(size 1.27 1.27)
					(thickness 0.15)
				)
			)
		)
		(property "Author" "Antmicro"
			(at 11.985 193.515 0)
			(layer "B.Fab")
			(hide yes)
			(effects
				(font
					(size 1 1)
					(thickness 0.15)
				)
				(justify mirror)
			)
		)
		(property "Dielectric" ""
			(at 11.985 193.515 0)
			(layer "B.Fab")
			(hide yes)
			(effects
				(font
					(size 1 1)
					(thickness 0.15)
				)
				(justify mirror)
			)
		)
		(property "License" "Apache-2.0"
			(at 11.985 193.515 0)
			(layer "B.Fab")
			(hide yes)
			(effects
				(font
					(size 1 1)
					(thickness 0.15)
				)
				(justify mirror)
			)
		)
		(property "MPN" "GRM155R61A475MEAAD"
			(at 11.985 193.515 0)
			(layer "B.Fab")
			(hide yes)
			(effects
				(font
					(size 1 1)
					(thickness 0.15)
				)
				(justify mirror)
			)
		)
		(property "Manufacturer" "Murata"
			(at 11.985 193.515 0)
			(layer "B.Fab")
			(hide yes)
			(effects
				(font
					(size 1 1)
					(thickness 0.15)
				)
				(justify mirror)
			)
		)
		(property "Val" "4u7"
			(at 11.985 193.515 0)
			(layer "B.Fab")
			(hide yes)
			(effects
				(font
					(size 1 1)
					(thickness 0.15)
				)
				(justify mirror)
			)
		)
		(property "Voltage" ""
			(at 11.985 193.515 0)
			(layer "B.Fab")
			(hide yes)
			(effects
				(font
					(size 1 1)
					(thickness 0.15)
				)
				(justify mirror)
			)
		)
		(sheetname "/Ethernet/")
		(sheetfile "ethernet.kicad_sch")
		(attr smd)
		(fp_rect
			(start -0.925 0.47)
			(end 0.925 -0.47)
			(stroke
				(width 0.05)
				(type default)
			)
			(fill no)
			(layer "B.CrtYd")
		)
		(fp_line
			(start -0.494 0.25)
			(end 0.504 0.25)
			(stroke
				(width 0.15)
				(type solid)
			)
			(layer "B.Fab")
		)
		(fp_line
			(start 0.504 0.25)
			(end 0.504 -0.248)
			(stroke
				(width 0.15)
				(type solid)
			)
			(layer "B.Fab")
		)
		(fp_line
			(start -0.494 -0.248)
			(end -0.494 0.25)
			(stroke
				(width 0.15)
				(type solid)
			)
			(layer "B.Fab")
		)
		(fp_line
			(start 0.504 -0.248)
			(end -0.494 -0.248)
			(stroke
				(width 0.15)
				(type solid)
			)
			(layer "B.Fab")
		)
		(pad "1" smd roundrect
			(at -0.48 0 270)
			(size 0.59 0.64)
			(layers "B.Cu" "B.Mask" "B.Paste")
			(roundrect_rratio 0.25)
			(net 1 "GND")
			(pintype "passive")
		)
		(pad "2" smd roundrect
			(at 0.48 0 270)
			(size 0.59 0.64)
			(layers "B.Cu" "B.Mask" "B.Paste")
			(roundrect_rratio 0.25)
			(net 405 "/Ethernet/AVDDL")
			(pintype "passive")
		)
	)
)
